(kicad_pcb
	(version 20260206)
	(generator "pcbnew")
	(generator_version "10.0")
	(general
		(thickness 1.6)
		(legacy_teardrops no)
	)
	(paper "A4")
	(title_block
		(title "pdpb — Lightning_PDPB_BRD.brd")
		(comment 1 "Lightning (Wiwynn / Facebook NVMe JBOF) / footprints 628-634 of 1140")
	)
	(layers
		(0 "F.Cu" signal "TOP")
		(4 "In1.Cu" signal "L2GND")
		(6 "In2.Cu" signal "L3")
		(8 "In3.Cu" signal "L4VCC")
		(10 "In4.Cu" signal "L5VCC")
		(12 "In5.Cu" signal "L6")
		(14 "In6.Cu" signal "L7GND")
		(2 "B.Cu" signal "BOTTOM")
		(9 "F.Adhes" user "F.Adhesive")
		(11 "B.Adhes" user "B.Adhesive")
		(13 "F.Paste" user "Package Geometry/Pastemask Top")
		(15 "B.Paste" user "Package Geometry/Pastemask Bottom")
		(5 "F.SilkS" user "Ref Des/Silkscreen Top")
		(7 "B.SilkS" user "Ref Des/Silkscreen Bottom")
		(1 "F.Mask" user "Board Geometry/Soldermask Top")
		(3 "B.Mask" user "Board Geometry/Soldermask Bottom")
		(17 "Dwgs.User" user "User.Drawings")
		(19 "Cmts.User" user "User.Comments")
		(21 "Eco1.User" user "User.Eco1")
		(23 "Eco2.User" user "User.Eco2")
		(25 "Edge.Cuts" user "Board Geometry/Outline")
		(27 "Margin" user)
		(31 "F.CrtYd" user "Package Geometry/Place Bound Top")
		(29 "B.CrtYd" user "Package Geometry/Place Bound Bottom")
		(35 "F.Fab" user "Ref Des/Assembly Top")
		(33 "B.Fab" user "Ref Des/Assembly Bottom")
	)
	(footprint ""
		(layer "F.Cu")
		(at 28.1432 -392.0998 90)
		(property "Reference" "SR1103"
			(at 0 0 90)
			(layer "F.SilkS")
			(hide yes)
			(effects
				(font
					(size 1.27 1.27)
				)
			)
		)
		(property "Value" "4K7R2F-GP"
			(at 0.064008 -3.993896 90)
			(unlocked yes)
			(layer "F.Fab")
			(hide yes)
			(effects
				(font
					(size 1.016 1.016)
					(thickness 0.1524)
				)
			)
		)
		(property "Device Type" "R402H16"
			(at 0.064008 -5.517896 90)
			(unlocked yes)
			(layer "F.Fab")
			(hide yes)
			(effects
				(font
					(size 1.016 1.016)
					(thickness 0.1524)
				)
			)
		)
		(duplicate_pad_numbers_are_jumpers no)
		(fp_line
			(start 0.508 -0.9398)
			(end -0.508 -0.9398)
			(stroke
				(width 0.1524)
				(type default)
			)
			(layer "F.SilkS")
		)
		(fp_line
			(start -0.508 -0.9398)
			(end -0.508 0.9398)
			(stroke
				(width 0.1524)
				(type default)
			)
			(layer "F.SilkS")
		)
		(fp_rect
			(start -0.508 0.9398)
			(end 0.508 -0.9398)
			(stroke
				(width 0)
				(type default)
			)
			(fill no)
			(layer "F.CrtYd")
		)
		(fp_rect
			(start -0.508 0.9398)
			(end 0.508 -0.9398)
			(stroke
				(width 0)
				(type default)
			)
			(fill no)
			(layer "F.Fab")
		)
		(pad "1" smd custom
			(at 0 -0.4445 90)
			(size 0.1397 0.1397)
			(layers "F.Cu" "F.Mask" "F.Paste")
			(net "P3V3")
			(options
				(clearance outline)
				(anchor circle)
			)
			(primitives
				(gr_poly
					(pts
						(arc
							(start -0.1778 -0.2794)
							(mid -0.249642 -0.249642)
							(end -0.2794 -0.1778)
						)
						(arc
							(start -0.2794 0.1778)
							(mid -0.249642 0.249642)
							(end -0.1778 0.2794)
						)
						(arc
							(start 0.1778 0.2794)
							(mid 0.249642 0.249642)
							(end 0.2794 0.1778)
						)
						(arc
							(start 0.2794 -0.1778)
							(mid 0.249642 -0.249642)
							(end 0.1778 -0.2794)
						)
					)
					(width 0)
					(fill yes)
				)
			)
		)
		(pad "2" smd custom
			(at 0 0.4445 90)
			(size 0.1397 0.1397)
			(layers "F.Cu" "F.Mask" "F.Paste")
			(net "DUALPORTEN#6")
			(options
				(clearance outline)
				(anchor circle)
			)
			(primitives
				(gr_poly
					(pts
						(arc
							(start -0.1778 -0.2794)
							(mid -0.249642 -0.249642)
							(end -0.2794 -0.1778)
						)
						(arc
							(start -0.2794 0.1778)
							(mid -0.249642 0.249642)
							(end -0.1778 0.2794)
						)
						(arc
							(start 0.1778 0.2794)
							(mid 0.249642 0.249642)
							(end 0.2794 0.1778)
						)
						(arc
							(start 0.2794 -0.1778)
							(mid 0.249642 -0.249642)
							(end 0.1778 -0.2794)
						)
					)
					(width 0)
					(fill yes)
				)
			)
		)
	)
	(footprint ""
		(layer "F.Cu")
		(at 35.0012 -292.2524)
		(property "Reference" "PC1246"
			(at 0 0 0)
			(layer "F.SilkS")
			(hide yes)
			(effects
				(font
					(size 1.27 1.27)
				)
			)
		)
		(property "Value" "SC22U25V6KX-GP-U"
			(at -2.860802 -5.279644 0)
			(unlocked yes)
			(layer "F.Fab")
			(hide yes)
			(effects
				(font
					(size 1.016 1.016)
					(thickness 0.1524)
				)
			)
		)
		(property "Device Type" "C1206-TO0D3H75"
			(at -2.860802 -6.803644 0)
			(unlocked yes)
			(layer "F.Fab")
			(hide yes)
			(effects
				(font
					(size 1.016 1.016)
					(thickness 0.1524)
				)
			)
		)
		(duplicate_pad_numbers_are_jumpers no)
		(fp_line
			(start -1.3081 -2.3749)
			(end 1.3081 -2.3749)
			(stroke
				(width 0.1524)
				(type default)
			)
			(layer "F.SilkS")
		)
		(fp_line
			(start -1.3081 2.3749)
			(end -1.3081 -2.3749)
			(stroke
				(width 0.1524)
				(type default)
			)
			(layer "F.SilkS")
		)
		(fp_line
			(start 1.3081 -2.3749)
			(end 1.3081 2.3749)
			(stroke
				(width 0.1524)
				(type default)
			)
			(layer "F.SilkS")
		)
		(fp_line
			(start 1.3081 2.3749)
			(end -1.3081 2.3749)
			(stroke
				(width 0.1524)
				(type default)
			)
			(layer "F.SilkS")
		)
		(fp_rect
			(start -0.8001 1.6002)
			(end 0.8001 -1.6002)
			(stroke
				(width 0)
				(type default)
			)
			(fill no)
			(layer "F.CrtYd")
		)
		(fp_poly
			(pts
				(xy -1.5621 2.4511) (xy -1.5621 1.6002) (xy 0.8001 1.6002) (xy 0.8001 -1.6002) (xy -0.8001 -1.6002)
				(xy -0.8001 1.5875) (xy -1.5621 1.5875) (xy -1.5621 -2.4511) (xy 1.5621 -2.4511) (xy 1.5621 2.4511)
			)
			(stroke
				(width 0)
				(type default)
			)
			(fill no)
			(layer "F.CrtYd")
		)
		(fp_poly
			(pts
				(xy -1.5621 2.4511) (xy 1.5621 2.4511) (xy 1.5621 -2.4511) (xy -1.5621 -2.4511)
			)
			(stroke
				(width 0)
				(type default)
			)
			(fill no)
			(layer "F.Fab")
		)
		(pad "1" smd rect
			(at 0 -1.392936)
			(size 2.1082 1.4478)
			(layers "F.Cu" "F.Mask" "F.Paste")
			(net "P12V_SSD7")
		)
		(pad "2" smd rect
			(at 0 1.392936)
			(size 2.1082 1.4478)
			(layers "F.Cu" "F.Mask" "F.Paste")
			(net "GND")
		)
	)
	(footprint ""
		(layer "F.Cu")
		(at 22.4028 -470.0016 180)
		(property "Reference" "U207"
			(at 0 0 180)
			(layer "F.SilkS")
			(hide yes)
			(effects
				(font
					(size 1.27 1.27)
				)
			)
		)
		(property "Value" "SN74LVC1G08DCKR-GP"
			(at -2.3368 -8.6868 180)
			(unlocked yes)
			(layer "F.Fab")
			(hide yes)
			(effects
				(font
					(size 1.016 1.016)
					(thickness 0.1524)
				)
			)
		)
		(property "Device Type" "SC70-5H44"
			(at -2.3114 -10.414 180)
			(unlocked yes)
			(layer "F.Fab")
			(hide yes)
			(effects
				(font
					(size 1.016 1.016)
					(thickness 0.1524)
				)
			)
		)
		(duplicate_pad_numbers_are_jumpers no)
		(fp_line
			(start 1.3843 -1.8034)
			(end 1.3843 -1.1176)
			(stroke
				(width 0.3302)
				(type default)
			)
			(layer "F.SilkS")
		)
		(fp_line
			(start 1.27 1.7018)
			(end -1.27 1.7018)
			(stroke
				(width 0.1524)
				(type default)
			)
			(layer "F.SilkS")
		)
		(fp_line
			(start 1.27 -1.7018)
			(end 1.27 1.7018)
			(stroke
				(width 0.1524)
				(type default)
			)
			(layer "F.SilkS")
		)
		(fp_line
			(start 0.6604 -1.8034)
			(end 1.3843 -1.8034)
			(stroke
				(width 0.3302)
				(type default)
			)
			(layer "F.SilkS")
		)
		(fp_line
			(start -1.27 1.7018)
			(end -1.27 -1.7018)
			(stroke
				(width 0.1524)
				(type default)
			)
			(layer "F.SilkS")
		)
		(fp_line
			(start -1.27 -1.7018)
			(end 1.27 -1.7018)
			(stroke
				(width 0.1524)
				(type default)
			)
			(layer "F.SilkS")
		)
		(fp_rect
			(start -1.524 1.9558)
			(end 1.524 -1.9558)
			(stroke
				(width 0)
				(type default)
			)
			(fill no)
			(layer "F.CrtYd")
		)
		(fp_poly
			(pts
				(xy -1.524 -1.9558) (xy 1.524 -1.9558) (xy 1.524 1.9558) (xy -1.524 1.9558)
			)
			(stroke
				(width 0)
				(type default)
			)
			(fill no)
			(layer "F.Fab")
		)
		(pad "1" smd rect
			(at 0.65024 -0.8255 180)
			(size 0.4064 1.2192)
			(layers "F.Cu" "F.Mask" "F.Paste")
			(net "SSD10_CLK0_OE_MOS_N")
		)
		(pad "2" smd rect
			(at 0 -0.8255 180)
			(size 0.4064 1.2192)
			(layers "F.Cu" "F.Mask" "F.Paste")
			(net "ATTN_LED_DR10_N")
		)
		(pad "3" smd rect
			(at -0.65024 -0.8255 180)
			(size 0.4064 1.2192)
			(layers "F.Cu" "F.Mask" "F.Paste")
			(net "GND")
		)
		(pad "4" smd rect
			(at -0.65024 0.8255 180)
			(size 0.4064 1.2192)
			(layers "F.Cu" "F.Mask" "F.Paste")
			(net "ATTN_LED_DR10_AND")
		)
		(pad "5" smd rect
			(at 0.65024 0.8255 180)
			(size 0.4064 1.2192)
			(layers "F.Cu" "F.Mask" "F.Paste")
			(net "P3V3")
		)
	)
	(footprint ""
		(layer "F.Cu")
		(at 81.661 -363.1438 -90)
		(property "Reference" "SR987"
			(at 0 0 270)
			(layer "F.SilkS")
			(hide yes)
			(effects
				(font
					(size 1.27 1.27)
				)
			)
		)
		(property "Value" "2KR2F-3-GP"
			(at 0.064008 -3.993896 270)
			(unlocked yes)
			(layer "F.Fab")
			(hide yes)
			(effects
				(font
					(size 1.016 1.016)
					(thickness 0.1524)
				)
			)
		)
		(property "Device Type" "R402H16"
			(at 0.064008 -5.517896 270)
			(unlocked yes)
			(layer "F.Fab")
			(hide yes)
			(effects
				(font
					(size 1.016 1.016)
					(thickness 0.1524)
				)
			)
		)
		(duplicate_pad_numbers_are_jumpers no)
		(fp_line
			(start -0.508 -0.9398)
			(end -0.508 0.9398)
			(stroke
				(width 0.1524)
				(type default)
			)
			(layer "F.SilkS")
		)
		(fp_line
			(start 0.508 -0.9398)
			(end -0.508 -0.9398)
			(stroke
				(width 0.1524)
				(type default)
			)
			(layer "F.SilkS")
		)
		(fp_rect
			(start -0.508 0.9398)
			(end 0.508 -0.9398)
			(stroke
				(width 0)
				(type default)
			)
			(fill no)
			(layer "F.CrtYd")
		)
		(fp_rect
			(start -0.508 0.9398)
			(end 0.508 -0.9398)
			(stroke
				(width 0)
				(type default)
			)
			(fill no)
			(layer "F.Fab")
		)
		(pad "1" smd custom
			(at 0 -0.4445 270)
			(size 0.1397 0.1397)
			(layers "F.Cu" "F.Mask" "F.Paste")
			(net "P3V3")
			(options
				(clearance outline)
				(anchor circle)
			)
			(primitives
				(gr_poly
					(pts
						(arc
							(start -0.1778 -0.2794)
							(mid -0.249642 -0.249642)
							(end -0.2794 -0.1778)
						)
						(arc
							(start -0.2794 0.1778)
							(mid -0.249642 0.249642)
							(end -0.1778 0.2794)
						)
						(arc
							(start 0.1778 0.2794)
							(mid 0.249642 0.249642)
							(end 0.2794 0.1778)
						)
						(arc
							(start 0.2794 -0.1778)
							(mid 0.249642 -0.249642)
							(end 0.1778 -0.2794)
						)
					)
					(width 0)
					(fill yes)
				)
			)
		)
		(pad "2" smd custom
			(at 0 0.4445 270)
			(size 0.1397 0.1397)
			(layers "F.Cu" "F.Mask" "F.Paste")
			(net "SDA_DR0")
			(options
				(clearance outline)
				(anchor circle)
			)
			(primitives
				(gr_poly
					(pts
						(arc
							(start -0.1778 -0.2794)
							(mid -0.249642 -0.249642)
							(end -0.2794 -0.1778)
						)
						(arc
							(start -0.2794 0.1778)
							(mid -0.249642 0.249642)
							(end -0.1778 0.2794)
						)
						(arc
							(start 0.1778 0.2794)
							(mid 0.249642 0.249642)
							(end 0.2794 0.1778)
						)
						(arc
							(start 0.2794 -0.1778)
							(mid 0.249642 -0.249642)
							(end 0.1778 -0.2794)
						)
					)
					(width 0)
					(fill yes)
				)
			)
		)
	)
	(footprint ""
		(layer "F.Cu")
		(at 24.003 -361.188 -90)
		(property "Reference" "R9436"
			(at 0 0 270)
			(layer "F.SilkS")
			(hide yes)
			(effects
				(font
					(size 1.27 1.27)
				)
			)
		)
		(property "Value" "100R2J-2-GP"
			(at 0.064008 -3.993896 270)
			(unlocked yes)
			(layer "F.Fab")
			(hide yes)
			(effects
				(font
					(size 1.016 1.016)
					(thickness 0.1524)
				)
			)
		)
		(property "Device Type" "R402H14"
			(at 0.064008 -5.517896 270)
			(unlocked yes)
			(layer "F.Fab")
			(hide yes)
			(effects
				(font
					(size 1.016 1.016)
					(thickness 0.1524)
				)
			)
		)
		(duplicate_pad_numbers_are_jumpers no)
		(fp_line
			(start -0.508 -0.9398)
			(end -0.508 0.9398)
			(stroke
				(width 0.1524)
				(type default)
			)
			(layer "F.SilkS")
		)
		(fp_line
			(start 0.508 -0.9398)
			(end -0.508 -0.9398)
			(stroke
				(width 0.1524)
				(type default)
			)
			(layer "F.SilkS")
		)
		(fp_rect
			(start -0.508 0.9398)
			(end 0.508 -0.9398)
			(stroke
				(width 0)
				(type default)
			)
			(fill no)
			(layer "F.CrtYd")
		)
		(fp_rect
			(start -0.508 0.9398)
			(end 0.508 -0.9398)
			(stroke
				(width 0)
				(type default)
			)
			(fill no)
			(layer "F.Fab")
		)
		(pad "1" smd custom
			(at 0 -0.4445 270)
			(size 0.1397 0.1397)
			(layers "F.Cu" "F.Mask" "F.Paste")
			(net "P3V3")
			(options
				(clearance outline)
				(anchor circle)
			)
			(primitives
				(gr_poly
					(pts
						(arc
							(start -0.1778 -0.2794)
							(mid -0.249642 -0.249642)
							(end -0.2794 -0.1778)
						)
						(arc
							(start -0.2794 0.1778)
							(mid -0.249642 0.249642)
							(end -0.1778 0.2794)
						)
						(arc
							(start 0.1778 0.2794)
							(mid 0.249642 0.249642)
							(end 0.2794 0.1778)
						)
						(arc
							(start 0.2794 -0.1778)
							(mid 0.249642 -0.249642)
							(end 0.1778 -0.2794)
						)
					)
					(width 0)
					(fill yes)
				)
			)
		)
		(pad "2" smd custom
			(at 0 0.4445 270)
			(size 0.1397 0.1397)
			(layers "F.Cu" "F.Mask" "F.Paste")
			(net "DRV_ACT_11")
			(options
				(clearance outline)
				(anchor circle)
			)
			(primitives
				(gr_poly
					(pts
						(arc
							(start -0.1778 -0.2794)
							(mid -0.249642 -0.249642)
							(end -0.2794 -0.1778)
						)
						(arc
							(start -0.2794 0.1778)
							(mid -0.249642 0.249642)
							(end -0.1778 0.2794)
						)
						(arc
							(start 0.1778 0.2794)
							(mid 0.249642 0.249642)
							(end 0.2794 0.1778)
						)
						(arc
							(start 0.2794 -0.1778)
							(mid 0.249642 -0.249642)
							(end 0.1778 -0.2794)
						)
					)
					(width 0)
					(fill yes)
				)
			)
		)
	)
	(footprint ""
		(layer "F.Cu")
		(at 77.4954 -102.1842 180)
		(property "Reference" "R9975"
			(at 0 0 180)
			(layer "F.SilkS")
			(hide yes)
			(effects
				(font
					(size 1.27 1.27)
				)
			)
		)
		(property "Value" "56R2F-1-GP"
			(at 0.064008 -3.993896 180)
			(unlocked yes)
			(layer "F.Fab")
			(hide yes)
			(effects
				(font
					(size 1.016 1.016)
					(thickness 0.1524)
				)
			)
		)
		(property "Device Type" "R402H16"
			(at 0.064008 -5.517896 180)
			(unlocked yes)
			(layer "F.Fab")
			(hide yes)
			(effects
				(font
					(size 1.016 1.016)
					(thickness 0.1524)
				)
			)
		)
		(duplicate_pad_numbers_are_jumpers no)
		(fp_line
			(start 0.508 -0.9398)
			(end -0.508 -0.9398)
			(stroke
				(width 0.1524)
				(type default)
			)
			(layer "F.SilkS")
		)
		(fp_line
			(start -0.508 -0.9398)
			(end -0.508 0.9398)
			(stroke
				(width 0.1524)
				(type default)
			)
			(layer "F.SilkS")
		)
		(fp_rect
			(start -0.508 0.9398)
			(end 0.508 -0.9398)
			(stroke
				(width 0)
				(type default)
			)
			(fill no)
			(layer "F.CrtYd")
		)
		(fp_rect
			(start -0.508 0.9398)
			(end 0.508 -0.9398)
			(stroke
				(width 0)
				(type default)
			)
			(fill no)
			(layer "F.Fab")
		)
		(pad "1" smd custom
			(at 0 -0.4445 180)
			(size 0.1397 0.1397)
			(layers "F.Cu" "F.Mask" "F.Paste")
			(net "PE_100M_CLK1_P")
			(options
				(clearance outline)
				(anchor circle)
			)
			(primitives
				(gr_poly
					(pts
						(arc
							(start -0.1778 -0.2794)
							(mid -0.249642 -0.249642)
							(end -0.2794 -0.1778)
						)
						(arc
							(start -0.2794 0.1778)
							(mid -0.249642 0.249642)
							(end -0.1778 0.2794)
						)
						(arc
							(start 0.1778 0.2794)
							(mid 0.249642 0.249642)
							(end 0.2794 0.1778)
						)
						(arc
							(start 0.2794 -0.1778)
							(mid 0.249642 -0.249642)
							(end 0.1778 -0.2794)
						)
					)
					(width 0)
					(fill yes)
				)
			)
		)
		(pad "2" smd custom
			(at 0 0.4445 180)
			(size 0.1397 0.1397)
			(layers "F.Cu" "F.Mask" "F.Paste")
			(net "GND")
			(options
				(clearance outline)
				(anchor circle)
			)
			(primitives
				(gr_poly
					(pts
						(arc
							(start -0.1778 -0.2794)
							(mid -0.249642 -0.249642)
							(end -0.2794 -0.1778)
						)
						(arc
							(start -0.2794 0.1778)
							(mid -0.249642 0.249642)
							(end -0.1778 0.2794)
						)
						(arc
							(start 0.1778 0.2794)
							(mid 0.249642 0.249642)
							(end 0.2794 0.1778)
						)
						(arc
							(start 0.2794 -0.1778)
							(mid 0.249642 -0.249642)
							(end 0.1778 -0.2794)
						)
					)
					(width 0)
					(fill yes)
				)
			)
		)
	)
	(footprint ""
		(layer "F.Cu")
		(at 19.547332 -159.002984 90)
		(property "Reference" "Q95"
			(at 0 0 90)
			(layer "F.SilkS")
			(hide yes)
			(effects
				(font
					(size 1.27 1.27)
				)
			)
		)
		(property "Value" "2N7002A-7-GP"
			(at 0.127 -8.9662 90)
			(unlocked yes)
			(layer "F.Fab")
			(hide yes)
			(effects
				(font
					(size 1.016 1.016)
					(thickness 0.1524)
				)
			)
		)
		(property "Device Type" "SOT23DGS2D4H48"
			(at 0.127 -10.4902 90)
			(unlocked yes)
			(layer "F.Fab")
			(hide yes)
			(effects
				(font
					(size 1.016 1.016)
					(thickness 0.1524)
				)
			)
		)
		(duplicate_pad_numbers_are_jumpers no)
		(fp_line
			(start 1.651 -1.778)
			(end -1.651 -1.778)
			(stroke
				(width 0.1524)
				(type default)
			)
			(layer "F.SilkS")
		)
		(fp_line
			(start -1.651 -1.778)
			(end -1.651 1.778)
			(stroke
				(width 0.1524)
				(type default)
			)
			(layer "F.SilkS")
		)
		(fp_line
			(start 1.651 1.778)
			(end 1.651 -1.778)
			(stroke
				(width 0.1524)
				(type default)
			)
			(layer "F.SilkS")
		)
		(fp_line
			(start -1.651 1.778)
			(end 1.651 1.778)
			(stroke
				(width 0.1524)
				(type default)
			)
			(layer "F.SilkS")
		)
		(fp_poly
			(pts
				(xy -1.778 1.8796) (xy -1.778 -1.8796) (xy 1.778 -1.8796) (xy 1.778 1.8796)
			)
			(stroke
				(width 0)
				(type default)
			)
			(fill no)
			(layer "F.CrtYd")
		)
		(fp_poly
			(pts
				(xy -1.778 1.8796) (xy -1.778 -1.8796) (xy 1.778 -1.8796) (xy 1.778 1.8796)
			)
			(stroke
				(width 0)
				(type default)
			)
			(fill no)
			(layer "F.Fab")
		)
		(pad "D" smd custom
			(at 0 -0.9525 90)
			(size 0.1905 0.1905)
			(layers "F.Cu" "F.Mask" "F.Paste")
			(net "ATTN_LED_DR13_MOS_N")
			(options
				(clearance outline)
				(anchor circle)
			)
			(primitives
				(gr_poly
					(pts
						(arc
							(start -0.1778 0.5715)
							(mid -0.321484 0.511984)
							(end -0.381 0.3683)
						)
						(arc
							(start -0.381 -0.3683)
							(mid -0.321484 -0.511984)
							(end -0.1778 -0.5715)
						)
						(arc
							(start 0.1778 -0.5715)
							(mid 0.321484 -0.511984)
							(end 0.381 -0.3683)
						)
						(arc
							(start 0.381 0.3683)
							(mid 0.321484 0.511984)
							(end 0.1778 0.5715)
						)
					)
					(width 0)
					(fill yes)
				)
			)
		)
		(pad "G" smd custom
			(at -0.98425 0.9525 90)
			(size 0.1905 0.1905)
			(layers "F.Cu" "F.Mask" "F.Paste")
			(net "SSD13_CLK0_OE_MOS_N")
			(options
				(clearance outline)
				(anchor circle)
			)
			(primitives
				(gr_poly
					(pts
						(arc
							(start -0.1778 0.5715)
							(mid -0.321484 0.511984)
							(end -0.381 0.3683)
						)
						(arc
							(start -0.381 -0.3683)
							(mid -0.321484 -0.511984)
							(end -0.1778 -0.5715)
						)
						(arc
							(start 0.1778 -0.5715)
							(mid 0.321484 -0.511984)
							(end 0.381 -0.3683)
						)
						(arc
							(start 0.381 0.3683)
							(mid 0.321484 0.511984)
							(end 0.1778 0.5715)
						)
					)
					(width 0)
					(fill yes)
				)
			)
		)
		(pad "S" smd custom
			(at 0.98425 0.9525 90)
			(size 0.1905 0.1905)
			(layers "F.Cu" "F.Mask" "F.Paste")
			(net "ATTN_LED_DR13_R")
			(options
				(clearance outline)
				(anchor circle)
			)
			(primitives
				(gr_poly
					(pts
						(arc
							(start -0.1778 0.5715)
							(mid -0.321484 0.511984)
							(end -0.381 0.3683)
						)
						(arc
							(start -0.381 -0.3683)
							(mid -0.321484 -0.511984)
							(end -0.1778 -0.5715)
						)
						(arc
							(start 0.1778 -0.5715)
							(mid 0.321484 -0.511984)
							(end 0.381 -0.3683)
						)
						(arc
							(start 0.381 0.3683)
							(mid 0.321484 0.511984)
							(end 0.1778 0.5715)
						)
					)
					(width 0)
					(fill yes)
				)
			)
		)
	)
)
